# T6G (Grand Teton) — schematic netlist excerpt (pin names and nets, part order shuffled) for the footprints in the layout excerpt that follows; sources: Cadence DE-HDL packaged netlist, KiCad conversion of 04192023_DAF0TMB3IC0_F0TG_MB_C_brd_V02_OCP.brd

R4601  Q_RES  0 5% CHIP  pkg 0402LF  page 133 : A = CLK_50M_NCSI_OCP_SFF_ISO ; B = CLK_50M_NCSI_OCP_SFF_ISO_R
PC364  Q_CAP  0.1UF 25V 10% X7R  pkg 0402  page 217 : A = PVDDCR_CPU1_P1_VINSEN ; B = GND

(kicad_pcb
	(version 20260206)
	(generator "pcbnew")
	(generator_version "10.0")
	(general
		(thickness 1.6)
		(legacy_teardrops no)
	)
	(paper "A4")
	(title_block
		(title "04192023_DAF0TMB3IC0_F0TG_MB_C_brd_V02_OCP.brd")
		(comment 1 "Grand Teton / footprints 322-323 of 8354")
	)
	(layers
		(0 "F.Cu" signal "TOP")
		(4 "In1.Cu" signal "GND")
		(6 "In2.Cu" signal "IN1")
		(8 "In3.Cu" signal "GND1")
		(10 "In4.Cu" signal "IN2")
		(12 "In5.Cu" signal "GND2")
		(14 "In6.Cu" signal "IN3")
		(16 "In7.Cu" signal "GND3")
		(18 "In8.Cu" signal "VCC")
		(20 "In9.Cu" signal "VCC1")
		(22 "In10.Cu" signal "GND4")
		(24 "In11.Cu" signal "IN4")
		(26 "In12.Cu" signal "GND5")
		(28 "In13.Cu" signal "IN5")
		(30 "In14.Cu" signal "GND6")
		(32 "In15.Cu" signal "IN6")
		(34 "In16.Cu" signal "GND7")
		(2 "B.Cu" signal "BOTTOM")
		(9 "F.Adhes" user "F.Adhesive")
		(11 "B.Adhes" user "B.Adhesive")
		(13 "F.Paste" user "Package Geometry/Pastemask Top")
		(15 "B.Paste" user "Package Geometry/Pastemask Bottom")
		(5 "F.SilkS" user "Ref Des/Silkscreen Top")
		(7 "B.SilkS" user "Ref Des/Silkscreen Bottom")
		(1 "F.Mask" user "Board Geometry/Soldermask Top")
		(3 "B.Mask" user "Board Geometry/Soldermask Bottom")
		(17 "Dwgs.User" user "User.Drawings")
		(19 "Cmts.User" user "User.Comments")
		(21 "Eco1.User" user "User.Eco1")
		(23 "Eco2.User" user "User.Eco2")
		(25 "Edge.Cuts" user "Board Geometry/Outline")
		(27 "Margin" user)
		(31 "F.CrtYd" user "Package Geometry/Place Bound Top")
		(29 "B.CrtYd" user "Package Geometry/Place Bound Bottom")
		(35 "F.Fab" user "Ref Des/Assembly Top")
		(33 "B.Fab" user "Ref Des/Assembly Bottom")
	)
	(footprint ""
		(layer "F.Cu")
		(at 36.449 -366.776 -90)
		(property "Reference" "PC364"
			(at 0 0 270)
			(layer "F.SilkS")
			(hide yes)
			(effects
				(font
					(size 1.27 1.27)
				)
			)
		)
		(property "Value" ""
			(at 0 0 270)
			(layer "F.Fab")
			(effects
				(font
					(size 1.27 1.27)
				)
			)
		)
		(duplicate_pad_numbers_are_jumpers no)
		(fp_line
			(start -0.7874 0.4064)
			(end -0.7874 -0.4064)
			(stroke
				(width 0.1524)
				(type default)
			)
			(layer "F.SilkS")
		)
		(fp_line
			(start 0.7874 0.4064)
			(end -0.7874 0.4064)
			(stroke
				(width 0.1524)
				(type default)
			)
			(layer "F.SilkS")
		)
		(fp_line
			(start -0.7874 -0.4064)
			(end 0.7874 -0.4064)
			(stroke
				(width 0.1524)
				(type default)
			)
			(layer "F.SilkS")
		)
		(fp_line
			(start 0.7874 -0.4064)
			(end 0.7874 0.4064)
			(stroke
				(width 0.1524)
				(type default)
			)
			(layer "F.SilkS")
		)
		(fp_line
			(start -0.67945 0.3048)
			(end -0.67945 -0.305054)
			(stroke
				(width 0.1)
				(type default)
			)
			(layer "F.Fab")
		)
		(fp_line
			(start -0.12065 0.3048)
			(end -0.67945 0.3048)
			(stroke
				(width 0.1)
				(type default)
			)
			(layer "F.Fab")
		)
		(fp_line
			(start 0.120396 0.3048)
			(end 0.120396 0.2794)
			(stroke
				(width 0.1)
				(type default)
			)
			(layer "F.Fab")
		)
		(fp_line
			(start 0.67945 0.3048)
			(end 0.120396 0.3048)
			(stroke
				(width 0.1)
				(type default)
			)
			(layer "F.Fab")
		)
		(fp_line
			(start -0.12065 0.2794)
			(end -0.12065 0.3048)
			(stroke
				(width 0.1)
				(type default)
			)
			(layer "F.Fab")
		)
		(fp_line
			(start 0.120396 0.2794)
			(end -0.12065 0.2794)
			(stroke
				(width 0.1)
				(type default)
			)
			(layer "F.Fab")
		)
		(fp_line
			(start -0.12065 -0.2794)
			(end 0.12065 -0.2794)
			(stroke
				(width 0.1)
				(type default)
			)
			(layer "F.Fab")
		)
		(fp_line
			(start 0.12065 -0.2794)
			(end 0.12065 -0.3048)
			(stroke
				(width 0.1)
				(type default)
			)
			(layer "F.Fab")
		)
		(fp_line
			(start 0.12065 -0.3048)
			(end 0.67945 -0.3048)
			(stroke
				(width 0.1)
				(type default)
			)
			(layer "F.Fab")
		)
		(fp_line
			(start 0.67945 -0.3048)
			(end 0.67945 0.3048)
			(stroke
				(width 0.1)
				(type default)
			)
			(layer "F.Fab")
		)
		(fp_line
			(start -0.67945 -0.305054)
			(end -0.12065 -0.305054)
			(stroke
				(width 0.1)
				(type default)
			)
			(layer "F.Fab")
		)
		(fp_line
			(start -0.12065 -0.305054)
			(end -0.12065 -0.2794)
			(stroke
				(width 0.1)
				(type default)
			)
			(layer "F.Fab")
		)
		(pad "1" smd circle
			(at -0.40005 0 270)
			(size 0 0)
			(layers "F.Cu" "F.Mask" "F.Paste")
			(net "PVDDCR_CPU1_P1_VINSEN")
		)
		(pad "2" smd circle
			(at 0.40005 0 270)
			(size 0 0)
			(layers "F.Cu" "F.Mask" "F.Paste")
			(net "GND")
		)
	)
	(footprint ""
		(layer "F.Cu")
		(at 385.049268 -33.226502 180)
		(property "Reference" "R4601"
			(at 0 0 180)
			(layer "F.SilkS")
			(hide yes)
			(effects
				(font
					(size 1.27 1.27)
				)
			)
		)
		(property "Value" ""
			(at 0 0 180)
			(layer "F.Fab")
			(effects
				(font
					(size 1.27 1.27)
				)
			)
		)
		(duplicate_pad_numbers_are_jumpers no)
		(fp_line
			(start 0.7874 0.4064)
			(end -0.7874 0.4064)
			(stroke
				(width 0.1524)
				(type default)
			)
			(layer "F.SilkS")
		)
		(fp_line
			(start 0.7874 -0.4064)
			(end 0.7874 0.4064)
			(stroke
				(width 0.1524)
				(type default)
			)
			(layer "F.SilkS")
		)
		(fp_line
			(start -0.7874 0.4064)
			(end -0.7874 -0.4064)
			(stroke
				(width 0.1524)
				(type default)
			)
			(layer "F.SilkS")
		)
		(fp_line
			(start -0.7874 -0.4064)
			(end 0.7874 -0.4064)
			(stroke
				(width 0.1524)
				(type default)
			)
			(layer "F.SilkS")
		)
		(fp_line
			(start 0.67945 0.3048)
			(end 0.120396 0.3048)
			(stroke
				(width 0.1)
				(type default)
			)
			(layer "F.Fab")
		)
		(fp_line
			(start 0.67945 -0.3048)
			(end 0.67945 0.3048)
			(stroke
				(width 0.1)
				(type default)
			)
			(layer "F.Fab")
		)
		(fp_line
			(start 0.12065 -0.2794)
			(end 0.12065 -0.3048)
			(stroke
				(width 0.1)
				(type default)
			)
			(layer "F.Fab")
		)
		(fp_line
			(start 0.12065 -0.3048)
			(end 0.67945 -0.3048)
			(stroke
				(width 0.1)
				(type default)
			)
			(layer "F.Fab")
		)
		(fp_line
			(start 0.120396 0.3048)
			(end 0.120396 0.2794)
			(stroke
				(width 0.1)
				(type default)
			)
			(layer "F.Fab")
		)
		(fp_line
			(start 0.120396 0.2794)
			(end -0.12065 0.2794)
			(stroke
				(width 0.1)
				(type default)
			)
			(layer "F.Fab")
		)
		(fp_line
			(start -0.12065 0.3048)
			(end -0.67945 0.3048)
			(stroke
				(width 0.1)
				(type default)
			)
			(layer "F.Fab")
		)
		(fp_line
			(start -0.12065 0.2794)
			(end -0.12065 0.3048)
			(stroke
				(width 0.1)
				(type default)
			)
			(layer "F.Fab")
		)
		(fp_line
			(start -0.12065 -0.2794)
			(end 0.12065 -0.2794)
			(stroke
				(width 0.1)
				(type default)
			)
			(layer "F.Fab")
		)
		(fp_line
			(start -0.12065 -0.305054)
			(end -0.12065 -0.2794)
			(stroke
				(width 0.1)
				(type default)
			)
			(layer "F.Fab")
		)
		(fp_line
			(start -0.67945 0.3048)
			(end -0.67945 -0.305054)
			(stroke
				(width 0.1)
				(type default)
			)
			(layer "F.Fab")
		)
		(fp_line
			(start -0.67945 -0.305054)
			(end -0.12065 -0.305054)
			(stroke
				(width 0.1)
				(type default)
			)
			(layer "F.Fab")
		)
		(pad "1" smd circle
			(at -0.40005 0 180)
			(size 0 0)
			(layers "F.Cu" "F.Mask" "F.Paste")
			(net "CLK_50M_NCSI_OCP_SFF_ISO")
		)
		(pad "2" smd circle
			(at 0.40005 0 180)
			(size 0 0)
			(layers "F.Cu" "F.Mask" "F.Paste")
			(net "CLK_50M_NCSI_OCP_SFF_ISO_R")
		)
	)
)
